# Bryce Canyon_Rear_Drive_Plane_Board_Stackup.xlsx — PCB Test Plan_HVM(90+) (pcb-stackup)
|  | Board vendor give feedback of quantity in yellow columns based on the AQL table or description. |  |  |  |  |  |  |  |  |  |  |  |  |  |  |
|  | Wiwynn PM give feedback in blue columns |  |  |  |  |  |  |  |  |  |  |  |  |  |  |
| Person to be informed : PCB vendor, EE, SI, PM, PSM, Buyer, SQM |  |  |  |  |  |  |  |  |  |  |  |  |  |  |  |
| Simple flow : SI (test requirements) -> PM/AM (Total PCBS demand) -> Buyer -> Board Vendor (yellow column feedback) -> Buyer -> Person to be informed (Check and Track) |  |  |  |  |  |  |  |  |  |  |  |  |  |  |  |
| PO(purchase order) : If there are many POs for this PCB, 1st sample quantity is based on 1st PO, 2nd sample quantity is based on 2nd PO. |  |  |  |  |  |  |  |  |  |  |  |  |  |  |  |
| Project Name | PCB name | PCB# (1XXXX-XX) | Product Stage | Batch# | PCB Vendor | Production  Lot size | PCBs Demand | Delta-L Coupon (PCB Vendor) | Delta-L Coupon (3rd Party Lab) | Impedance Coupon (PCB Vendor) | In-board trace correlation (PCB Vendor) | X-section Analysis (PCB Vendor) | IST (3rd Party Lab) | IPC-6012D (3rd Party Lab) | Note |
| Bryce Canyon | RDPB | 16317-1 | HVM(90+ days) | N/A |  |  | TBD | Yes | No | Yes | No | No | No | No | Need Test? (Yes, No) |
| Tracking Code On Both Of Coupon And PCB |  |  |  |  |  |  |  | N/A |  | N/A |  |  |  |  |  |
| Test Item Acceptance Criteria |  |  |  |  |  |  |  | c = 0 |  | c = 0 |  |  |  |  |  |
| Test Item Sampling Quantity |  |  |  |  |  |  |  | 5 pcs/production lot/quarter, with max total of 30 pcs |  | Mil-STD 105E single sampling plan, AQL 0.65, level 2 |  |  |  |  |  |
| Test Time (working days) |  |  |  |  |  |  |  |  |  |  |  |  |  |  |  |
| Test Item Shipping Quantity |  |  |  |  |  |  |  |  |  |  |  |  |  |  |  |
| Shipping Address |  |  |  |  |  |  |  |  |  |  |  |  |  |  |  |
| Receiver Name |  |  |  |  |  |  |  |  |  |  |  |  |  |  |  |
| Receiver Phone# |  |  |  |  |  |  |  |  |  |  |  |  |  |  |  |
